# S9S_MB_2U (Grand Teton) — schematic netlist excerpt (pin names and nets, part order shuffled) for the footprints in the layout excerpt that follows; sources: Cadence DE-HDL packaged netlist, KiCad conversion of 03242023_DA0F0TMBIJ0_F0T_Motherboard_J_brd_V01_OCP.brd

R2941  Q_RES  100K 1% CHIP  pkg 0402LF  page 246 : A = FM_GPU_HSC_EN ; B = GND

Q78  MOSFET_NCH_DUAL  PJT138K IC  pkg SOT363XD  page 252
  S1  = GND
  G1  = FM_PCH_SLP_S3_N
  D2  = LED_PWRGD_PS_PWROK_PLD_D
  S2  = GND
  G2  = PWRGD_PS_PWROK_PLD
  D1  = LED_FM_PCH_SLP_S3_N_D

(kicad_pcb
	(version 20260206)
	(generator "pcbnew")
	(generator_version "10.0")
	(general
		(thickness 1.6)
		(legacy_teardrops no)
	)
	(paper "A4")
	(title_block
		(title "03242023_DA0F0TMBIJ0_F0T_Motherboard_J_brd_V01_OCP.brd")
		(comment 1 "Grand Teton / footprints 2823-2824 of 6105")
	)
	(layers
		(0 "F.Cu" signal "TOP")
		(4 "In1.Cu" signal "GND")
		(6 "In2.Cu" signal "IN1")
		(8 "In3.Cu" signal "GND1")
		(10 "In4.Cu" signal "IN2")
		(12 "In5.Cu" signal "GND2")
		(14 "In6.Cu" signal "IN3")
		(16 "In7.Cu" signal "GND3")
		(18 "In8.Cu" signal "VCC")
		(20 "In9.Cu" signal "VCC1")
		(22 "In10.Cu" signal "GND4")
		(24 "In11.Cu" signal "IN4")
		(26 "In12.Cu" signal "GND5")
		(28 "In13.Cu" signal "IN5")
		(30 "In14.Cu" signal "GND6")
		(32 "In15.Cu" signal "IN6")
		(34 "In16.Cu" signal "GND7")
		(2 "B.Cu" signal "BOTTOM")
		(9 "F.Adhes" user "F.Adhesive")
		(11 "B.Adhes" user "B.Adhesive")
		(13 "F.Paste" user "Package Geometry/Pastemask Top")
		(15 "B.Paste" user "Package Geometry/Pastemask Bottom")
		(5 "F.SilkS" user "Ref Des/Silkscreen Top")
		(7 "B.SilkS" user "Ref Des/Silkscreen Bottom")
		(1 "F.Mask" user "Board Geometry/Soldermask Top")
		(3 "B.Mask" user "Board Geometry/Soldermask Bottom")
		(17 "Dwgs.User" user "User.Drawings")
		(19 "Cmts.User" user "User.Comments")
		(21 "Eco1.User" user "User.Eco1")
		(23 "Eco2.User" user "User.Eco2")
		(25 "Edge.Cuts" user "Board Geometry/Outline")
		(27 "Margin" user)
		(31 "F.CrtYd" user "Package Geometry/Place Bound Top")
		(29 "B.CrtYd" user "Package Geometry/Place Bound Bottom")
		(35 "F.Fab" user "Ref Des/Assembly Top")
		(33 "B.Fab" user "Ref Des/Assembly Bottom")
	)
	(footprint ""
		(layer "F.Cu")
		(at 193.893186 -438.17413 90)
		(property "Reference" "R2941"
			(at 0 0 90)
			(layer "F.SilkS")
			(hide yes)
			(effects
				(font
					(size 1.27 1.27)
				)
			)
		)
		(property "Value" ""
			(at 0 0 90)
			(layer "F.Fab")
			(effects
				(font
					(size 1.27 1.27)
				)
			)
		)
		(duplicate_pad_numbers_are_jumpers no)
		(fp_line
			(start 0.7874 -0.4064)
			(end 0.7874 0.4064)
			(stroke
				(width 0.1524)
				(type default)
			)
			(layer "F.SilkS")
		)
		(fp_line
			(start -0.7874 -0.4064)
			(end 0.7874 -0.4064)
			(stroke
				(width 0.1524)
				(type default)
			)
			(layer "F.SilkS")
		)
		(fp_line
			(start 0.7874 0.4064)
			(end -0.7874 0.4064)
			(stroke
				(width 0.1524)
				(type default)
			)
			(layer "F.SilkS")
		)
		(fp_line
			(start -0.7874 0.4064)
			(end -0.7874 -0.4064)
			(stroke
				(width 0.1524)
				(type default)
			)
			(layer "F.SilkS")
		)
		(fp_line
			(start -0.12065 -0.305054)
			(end -0.12065 -0.2794)
			(stroke
				(width 0.1)
				(type default)
			)
			(layer "F.Fab")
		)
		(fp_line
			(start -0.67945 -0.305054)
			(end -0.12065 -0.305054)
			(stroke
				(width 0.1)
				(type default)
			)
			(layer "F.Fab")
		)
		(fp_line
			(start 0.67945 -0.3048)
			(end 0.67945 0.3048)
			(stroke
				(width 0.1)
				(type default)
			)
			(layer "F.Fab")
		)
		(fp_line
			(start 0.12065 -0.3048)
			(end 0.67945 -0.3048)
			(stroke
				(width 0.1)
				(type default)
			)
			(layer "F.Fab")
		)
		(fp_line
			(start 0.12065 -0.2794)
			(end 0.12065 -0.3048)
			(stroke
				(width 0.1)
				(type default)
			)
			(layer "F.Fab")
		)
		(fp_line
			(start -0.12065 -0.2794)
			(end 0.12065 -0.2794)
			(stroke
				(width 0.1)
				(type default)
			)
			(layer "F.Fab")
		)
		(fp_line
			(start 0.120396 0.2794)
			(end -0.12065 0.2794)
			(stroke
				(width 0.1)
				(type default)
			)
			(layer "F.Fab")
		)
		(fp_line
			(start -0.12065 0.2794)
			(end -0.12065 0.3048)
			(stroke
				(width 0.1)
				(type default)
			)
			(layer "F.Fab")
		)
		(fp_line
			(start 0.67945 0.3048)
			(end 0.120396 0.3048)
			(stroke
				(width 0.1)
				(type default)
			)
			(layer "F.Fab")
		)
		(fp_line
			(start 0.120396 0.3048)
			(end 0.120396 0.2794)
			(stroke
				(width 0.1)
				(type default)
			)
			(layer "F.Fab")
		)
		(fp_line
			(start -0.12065 0.3048)
			(end -0.67945 0.3048)
			(stroke
				(width 0.1)
				(type default)
			)
			(layer "F.Fab")
		)
		(fp_line
			(start -0.67945 0.3048)
			(end -0.67945 -0.305054)
			(stroke
				(width 0.1)
				(type default)
			)
			(layer "F.Fab")
		)
		(pad "1" smd circle
			(at -0.40005 0 90)
			(size 0 0)
			(layers "F.Cu" "F.Mask" "F.Paste")
			(net "FM_GPU_HSC_EN")
		)
		(pad "2" smd circle
			(at 0.40005 0 90)
			(size 0 0)
			(layers "F.Cu" "F.Mask" "F.Paste")
			(net "GND")
		)
	)
	(footprint ""
		(layer "F.Cu")
		(at 100.94849 -92.87256)
		(property "Reference" "Q78"
			(at 1.61544 -0.762508 0)
			(unlocked yes)
			(layer "F.SilkS")
			(effects
				(font
					(size 0.7874 0.5842)
					(thickness 0.1524)
				)
				(justify left)
			)
		)
		(property "Value" ""
			(at 0 0 0)
			(layer "F.Fab")
			(effects
				(font
					(size 1.27 1.27)
				)
			)
		)
		(duplicate_pad_numbers_are_jumpers no)
		(fp_line
			(start -1.332738 -1.100074)
			(end -0.4826 -1.100074)
			(stroke
				(width 0.1524)
				(type default)
			)
			(layer "F.SilkS")
		)
		(fp_line
			(start -1.332738 1.100074)
			(end -1.332738 -1.100074)
			(stroke
				(width 0.1524)
				(type default)
			)
			(layer "F.SilkS")
		)
		(fp_line
			(start -0.4826 -1.100074)
			(end 0 -0.541274)
			(stroke
				(width 0.1524)
				(type default)
			)
			(layer "F.SilkS")
		)
		(fp_line
			(start 0 -0.541274)
			(end 0.4826 -1.100074)
			(stroke
				(width 0.1524)
				(type default)
			)
			(layer "F.SilkS")
		)
		(fp_line
			(start 0.4826 -1.100074)
			(end 1.332738 -1.100074)
			(stroke
				(width 0.1524)
				(type default)
			)
			(layer "F.SilkS")
		)
		(fp_line
			(start 1.332738 -1.100074)
			(end 1.332738 1.100074)
			(stroke
				(width 0.1524)
				(type default)
			)
			(layer "F.SilkS")
		)
		(fp_line
			(start 1.332738 1.100074)
			(end -1.332738 1.100074)
			(stroke
				(width 0.1524)
				(type default)
			)
			(layer "F.SilkS")
		)
		(fp_poly
			(pts
				(xy -1.809242 -1.854962) (xy -1.561084 -1.110488) (xy -2.305812 -1.358646)
			)
			(stroke
				(width 0)
				(type default)
			)
			(fill yes)
			(layer "F.SilkS")
		)
		(fp_line
			(start -0.674878 -1.100074)
			(end 0.674878 -1.100074)
			(stroke
				(width 0.1)
				(type default)
			)
			(layer "F.Fab")
		)
		(fp_line
			(start -0.674878 1.100074)
			(end -0.674878 -1.100074)
			(stroke
				(width 0.1)
				(type default)
			)
			(layer "F.Fab")
		)
		(fp_line
			(start 0.674878 -1.100074)
			(end 0.674878 1.100074)
			(stroke
				(width 0.1)
				(type default)
			)
			(layer "F.Fab")
		)
		(fp_line
			(start 0.674878 1.100074)
			(end -0.674878 1.100074)
			(stroke
				(width 0.1)
				(type default)
			)
			(layer "F.Fab")
		)
		(fp_poly
			(pts
				(xy -2.2352 -0.298958) (xy -2.2352 -1.001014) (xy -1.533144 -0.649986)
			)
			(stroke
				(width 0)
				(type default)
			)
			(fill yes)
			(layer "F.Fab")
		)
		(pad "1" smd rect
			(at -0.94996 -0.649986 90)
			(size 0.4318 0.508)
			(layers "F.Cu" "F.Mask" "F.Paste")
			(net "GND")
		)
		(pad "2" smd rect
			(at -0.94996 0 90)
			(size 0.4318 0.508)
			(layers "F.Cu" "F.Mask" "F.Paste")
			(net "FM_PCH_SLP_S3_N")
		)
		(pad "3" smd rect
			(at -0.94996 0.649986 90)
			(size 0.4318 0.508)
			(layers "F.Cu" "F.Mask" "F.Paste")
			(net "LED_PWRGD_PS_PWROK_PLD_D")
		)
		(pad "4" smd rect
			(at 0.94996 0.649986 90)
			(size 0.4318 0.508)
			(layers "F.Cu" "F.Mask" "F.Paste")
			(net "GND")
		)
		(pad "5" smd rect
			(at 0.94996 0 90)
			(size 0.4318 0.508)
			(layers "F.Cu" "F.Mask" "F.Paste")
			(net "PWRGD_PS_PWROK_PLD")
		)
		(pad "6" smd rect
			(at 0.94996 -0.649986 90)
			(size 0.4318 0.508)
			(layers "F.Cu" "F.Mask" "F.Paste")
			(net "LED_FM_PCH_SLP_S3_N_D")
		)
	)
)
